(kicad_pcb
	(version 20260206)
	(generator "pcbnew")
	(generator_version "10.0")
	(general
		(thickness 1.6)
		(legacy_teardrops no)
	)
	(paper "A4")
	(title_block
		(title "Bryce Canyon_IOM_M2_16342-2_OCP.brd")
		(comment 1 "Bryce Canyon / footprints 837-843 of 1146")
	)
	(layers
		(0 "F.Cu" signal "TOP")
		(4 "In1.Cu" signal "L2GND")
		(6 "In2.Cu" signal "L3")
		(8 "In3.Cu" signal "L4VCC")
		(10 "In4.Cu" signal "L5VCC")
		(12 "In5.Cu" signal "L6")
		(14 "In6.Cu" signal "L7GND")
		(2 "B.Cu" signal "BOTTOM")
		(9 "F.Adhes" user "F.Adhesive")
		(11 "B.Adhes" user "B.Adhesive")
		(13 "F.Paste" user "Package Geometry/Pastemask Top")
		(15 "B.Paste" user "Package Geometry/Pastemask Bottom")
		(5 "F.SilkS" user "Ref Des/Silkscreen Top")
		(7 "B.SilkS" user "Ref Des/Silkscreen Bottom")
		(1 "F.Mask" user "Board Geometry/Soldermask Top")
		(3 "B.Mask" user "Board Geometry/Soldermask Bottom")
		(17 "Dwgs.User" user "User.Drawings")
		(19 "Cmts.User" user "User.Comments")
		(21 "Eco1.User" user "User.Eco1")
		(23 "Eco2.User" user "User.Eco2")
		(25 "Edge.Cuts" user "Board Geometry/Outline")
		(27 "Margin" user)
		(31 "F.CrtYd" user "Package Geometry/Place Bound Top")
		(29 "B.CrtYd" user "Package Geometry/Place Bound Bottom")
		(35 "F.Fab" user "Ref Des/Assembly Top")
		(33 "B.Fab" user "Ref Des/Assembly Bottom")
	)
	(footprint ""
		(layer "B.Cu")
		(at 168.617138 -9.171178)
		(property "Reference" "C215"
			(at 0 0 0)
			(layer "B.SilkS")
			(hide yes)
			(effects
				(font
					(size 1.27 1.27)
				)
				(justify mirror)
			)
		)
		(property "Value" "SC10U6D3V5KX-4GP"
			(at 0.0762 -6.1214 0)
			(unlocked yes)
			(layer "B.Fab")
			(hide yes)
			(effects
				(font
					(size 1.016 1.016)
					(thickness 0.1524)
				)
				(justify mirror)
			)
		)
		(property "Device Type" "C805H58"
			(at 0.0762 -8.1534 0)
			(unlocked yes)
			(layer "B.Fab")
			(hide yes)
			(effects
				(font
					(size 1.016 1.016)
					(thickness 0.1524)
				)
				(justify mirror)
			)
		)
		(duplicate_pad_numbers_are_jumpers no)
		(fp_line
			(start -0.635 0)
			(end 0.635 0)
			(stroke
				(width 0.508)
				(type default)
			)
			(layer "B.SilkS")
		)
		(fp_rect
			(start 0.9652 1.778)
			(end -0.9652 -1.778)
			(stroke
				(width 0)
				(type default)
			)
			(fill no)
			(layer "B.CrtYd")
		)
		(fp_poly
			(pts
				(xy 0.9652 -1.778) (xy -0.9652 -1.778) (xy -0.9652 1.778) (xy 0.9652 1.778)
			)
			(stroke
				(width 0)
				(type default)
			)
			(fill no)
			(layer "B.Fab")
		)
		(pad "1" smd rect
			(at 0 -0.9652 180)
			(size 1.397 1.143)
			(layers "B.Cu" "B.Mask" "B.Paste")
			(net "P1V8_STBY")
		)
		(pad "2" smd rect
			(at 0 0.9652 180)
			(size 1.397 1.143)
			(layers "B.Cu" "B.Mask" "B.Paste")
			(net "GND")
		)
	)
	(footprint ""
		(layer "B.Cu")
		(at 58.3438 -144.018 -90)
		(property "Reference" "R358"
			(at 0 0 90)
			(layer "B.SilkS")
			(hide yes)
			(effects
				(font
					(size 1.27 1.27)
				)
				(justify mirror)
			)
		)
		(property "Value" "10KR2F-2-GP"
			(at -0.064008 -3.993896 270)
			(unlocked yes)
			(layer "B.Fab")
			(hide yes)
			(effects
				(font
					(size 1.016 1.016)
					(thickness 0.1524)
				)
				(justify mirror)
			)
		)
		(property "Device Type" "R402H16"
			(at -0.064008 -5.517896 270)
			(unlocked yes)
			(layer "B.Fab")
			(hide yes)
			(effects
				(font
					(size 1.016 1.016)
					(thickness 0.1524)
				)
				(justify mirror)
			)
		)
		(duplicate_pad_numbers_are_jumpers no)
		(fp_line
			(start -0.508 -0.9398)
			(end 0.508 -0.9398)
			(stroke
				(width 0.1524)
				(type default)
			)
			(layer "B.SilkS")
		)
		(fp_line
			(start 0.508 -0.9398)
			(end 0.508 0.9398)
			(stroke
				(width 0.1524)
				(type default)
			)
			(layer "B.SilkS")
		)
		(fp_rect
			(start 0.508 0.9398)
			(end -0.508 -0.9398)
			(stroke
				(width 0)
				(type default)
			)
			(fill no)
			(layer "B.CrtYd")
		)
		(fp_rect
			(start 0.508 0.9398)
			(end -0.508 -0.9398)
			(stroke
				(width 0)
				(type default)
			)
			(fill no)
			(layer "B.Fab")
		)
		(pad "1" smd custom
			(at 0 -0.4445 90)
			(size 0.1397 0.1397)
			(layers "B.Cu" "B.Mask" "B.Paste")
			(net "P3V3_STBY")
			(options
				(clearance outline)
				(anchor circle)
			)
			(primitives
				(gr_poly
					(pts
						(arc
							(start -0.1778 0.2794)
							(mid -0.249642 0.249642)
							(end -0.2794 0.1778)
						)
						(arc
							(start -0.2794 -0.1778)
							(mid -0.249642 -0.249642)
							(end -0.1778 -0.2794)
						)
						(arc
							(start 0.1778 -0.2794)
							(mid 0.249642 -0.249642)
							(end 0.2794 -0.1778)
						)
						(arc
							(start 0.2794 0.1778)
							(mid 0.249642 0.249642)
							(end 0.1778 0.2794)
						)
					)
					(width 0)
					(fill yes)
				)
			)
		)
		(pad "2" smd custom
			(at 0 0.4445 90)
			(size 0.1397 0.1397)
			(layers "B.Cu" "B.Mask" "B.Paste")
			(net "JTAG_BMC_TDI")
			(options
				(clearance outline)
				(anchor circle)
			)
			(primitives
				(gr_poly
					(pts
						(arc
							(start -0.1778 0.2794)
							(mid -0.249642 0.249642)
							(end -0.2794 0.1778)
						)
						(arc
							(start -0.2794 -0.1778)
							(mid -0.249642 -0.249642)
							(end -0.1778 -0.2794)
						)
						(arc
							(start 0.1778 -0.2794)
							(mid 0.249642 -0.249642)
							(end 0.2794 -0.1778)
						)
						(arc
							(start 0.2794 0.1778)
							(mid 0.249642 0.249642)
							(end 0.1778 0.2794)
						)
					)
					(width 0)
					(fill yes)
				)
			)
		)
	)
	(footprint ""
		(layer "B.Cu")
		(at 88.6968 -161.2646 180)
		(property "Reference" "C15"
			(at 0 0 0)
			(layer "B.SilkS")
			(hide yes)
			(effects
				(font
					(size 1.27 1.27)
				)
				(justify mirror)
			)
		)
		(property "Value" "SC1U16V3KX-5GP"
			(at 0 -2.8194 180)
			(unlocked yes)
			(layer "B.Fab")
			(hide yes)
			(effects
				(font
					(size 1.016 1.016)
					(thickness 0.1524)
				)
				(justify mirror)
			)
		)
		(property "Device Type" "C603H36"
			(at 0 -4.3434 180)
			(unlocked yes)
			(layer "B.Fab")
			(hide yes)
			(effects
				(font
					(size 1.016 1.016)
					(thickness 0.1524)
				)
				(justify mirror)
			)
		)
		(duplicate_pad_numbers_are_jumpers no)
		(fp_line
			(start -0.508 0)
			(end 0.508 0)
			(stroke
				(width 0.2032)
				(type default)
			)
			(layer "B.SilkS")
		)
		(fp_rect
			(start 0.5842 1.3335)
			(end -0.5842 -1.3335)
			(stroke
				(width 0)
				(type default)
			)
			(fill no)
			(layer "B.CrtYd")
		)
		(fp_rect
			(start 0.5842 1.3335)
			(end -0.5842 -1.3335)
			(stroke
				(width 0)
				(type default)
			)
			(fill no)
			(layer "B.Fab")
		)
		(pad "1" smd custom
			(at 0 -0.762)
			(size 0.2159 0.2159)
			(layers "B.Cu" "B.Mask" "B.Paste")
			(net "P3V3_STBY")
			(options
				(clearance outline)
				(anchor circle)
			)
			(primitives
				(gr_poly
					(pts
						(arc
							(start -0.3302 0.4318)
							(mid -0.402042 0.402042)
							(end -0.4318 0.3302)
						)
						(arc
							(start -0.4318 -0.3302)
							(mid -0.402042 -0.402042)
							(end -0.3302 -0.4318)
						)
						(arc
							(start 0.3302 -0.4318)
							(mid 0.402042 -0.402042)
							(end 0.4318 -0.3302)
						)
						(arc
							(start 0.4318 0.3302)
							(mid 0.402042 0.402042)
							(end 0.3302 0.4318)
						)
					)
					(width 0)
					(fill yes)
				)
			)
		)
		(pad "2" smd custom
			(at 0 0.762)
			(size 0.2159 0.2159)
			(layers "B.Cu" "B.Mask" "B.Paste")
			(net "GND")
			(options
				(clearance outline)
				(anchor circle)
			)
			(primitives
				(gr_poly
					(pts
						(arc
							(start -0.3302 0.4318)
							(mid -0.402042 0.402042)
							(end -0.4318 0.3302)
						)
						(arc
							(start -0.4318 -0.3302)
							(mid -0.402042 -0.402042)
							(end -0.3302 -0.4318)
						)
						(arc
							(start 0.3302 -0.4318)
							(mid 0.402042 -0.402042)
							(end 0.4318 -0.3302)
						)
						(arc
							(start 0.4318 0.3302)
							(mid 0.402042 0.402042)
							(end 0.3302 0.4318)
						)
					)
					(width 0)
					(fill yes)
				)
			)
		)
	)
	(footprint ""
		(layer "B.Cu")
		(at 81.1784 -130.2766 -90)
		(property "Reference" "U103"
			(at 0 0 90)
			(layer "B.SilkS")
			(hide yes)
			(effects
				(font
					(size 1.27 1.27)
				)
				(justify mirror)
			)
		)
		(property "Value" "SNLVC1G126DCKR-GP"
			(at 2.3368 -8.6868 270)
			(unlocked yes)
			(layer "B.Fab")
			(hide yes)
			(effects
				(font
					(size 1.016 1.016)
					(thickness 0.1524)
				)
				(justify mirror)
			)
		)
		(property "Device Type" "SC70-5H44"
			(at 2.3114 -10.414 270)
			(unlocked yes)
			(layer "B.Fab")
			(hide yes)
			(effects
				(font
					(size 1.016 1.016)
					(thickness 0.1524)
				)
				(justify mirror)
			)
		)
		(duplicate_pad_numbers_are_jumpers no)
		(fp_line
			(start -1.27 1.7018)
			(end 1.27 1.7018)
			(stroke
				(width 0.1524)
				(type default)
			)
			(layer "B.SilkS")
		)
		(fp_line
			(start 1.27 1.7018)
			(end 1.27 -1.7018)
			(stroke
				(width 0.1524)
				(type default)
			)
			(layer "B.SilkS")
		)
		(fp_line
			(start -1.27 -1.7018)
			(end -1.27 1.7018)
			(stroke
				(width 0.1524)
				(type default)
			)
			(layer "B.SilkS")
		)
		(fp_line
			(start 1.27 -1.7018)
			(end -1.27 -1.7018)
			(stroke
				(width 0.1524)
				(type default)
			)
			(layer "B.SilkS")
		)
		(fp_line
			(start -1.3843 -1.8034)
			(end -1.3843 -1.1176)
			(stroke
				(width 0.3302)
				(type default)
			)
			(layer "B.SilkS")
		)
		(fp_line
			(start -0.6604 -1.8034)
			(end -1.3843 -1.8034)
			(stroke
				(width 0.3302)
				(type default)
			)
			(layer "B.SilkS")
		)
		(fp_rect
			(start 1.524 1.9558)
			(end -1.524 -1.9558)
			(stroke
				(width 0)
				(type default)
			)
			(fill no)
			(layer "B.CrtYd")
		)
		(fp_poly
			(pts
				(xy 1.524 -1.9558) (xy -1.524 -1.9558) (xy -1.524 1.9558) (xy 1.524 1.9558)
			)
			(stroke
				(width 0)
				(type default)
			)
			(fill no)
			(layer "B.Fab")
		)
		(pad "1" smd rect
			(at -0.65024 -0.8255 90)
			(size 0.4064 1.2192)
			(layers "B.Cu" "B.Mask" "B.Paste")
			(net "PWRGD_P3V3_STBY")
		)
		(pad "2" smd rect
			(at 0 -0.8255 90)
			(size 0.4064 1.2192)
			(layers "B.Cu" "B.Mask" "B.Paste")
			(net "BMC_TO_EXP_RESET_OUT_R")
		)
		(pad "3" smd rect
			(at 0.65024 -0.8255 90)
			(size 0.4064 1.2192)
			(layers "B.Cu" "B.Mask" "B.Paste")
			(net "GND")
		)
		(pad "4" smd rect
			(at 0.65024 0.8255 90)
			(size 0.4064 1.2192)
			(layers "B.Cu" "B.Mask" "B.Paste")
			(net "BMC_TO_EXP_RESET_N")
		)
		(pad "5" smd rect
			(at -0.65024 0.8255 90)
			(size 0.4064 1.2192)
			(layers "B.Cu" "B.Mask" "B.Paste")
			(net "P3V3_STBY")
		)
	)
	(footprint ""
		(layer "B.Cu")
		(at 92.456 -146.0246 90)
		(property "Reference" "R425"
			(at 0 0 90)
			(layer "B.SilkS")
			(hide yes)
			(effects
				(font
					(size 1.27 1.27)
				)
				(justify mirror)
			)
		)
		(property "Value" "4K7R2F-GP"
			(at -0.064008 -3.993896 90)
			(unlocked yes)
			(layer "B.Fab")
			(hide yes)
			(effects
				(font
					(size 1.016 1.016)
					(thickness 0.1524)
				)
				(justify mirror)
			)
		)
		(property "Device Type" "R402H16"
			(at -0.064008 -5.517896 90)
			(unlocked yes)
			(layer "B.Fab")
			(hide yes)
			(effects
				(font
					(size 1.016 1.016)
					(thickness 0.1524)
				)
				(justify mirror)
			)
		)
		(duplicate_pad_numbers_are_jumpers no)
		(fp_line
			(start 0.508 -0.9398)
			(end 0.508 0.9398)
			(stroke
				(width 0.1524)
				(type default)
			)
			(layer "B.SilkS")
		)
		(fp_line
			(start -0.508 -0.9398)
			(end 0.508 -0.9398)
			(stroke
				(width 0.1524)
				(type default)
			)
			(layer "B.SilkS")
		)
		(fp_rect
			(start 0.508 0.9398)
			(end -0.508 -0.9398)
			(stroke
				(width 0)
				(type default)
			)
			(fill no)
			(layer "B.CrtYd")
		)
		(fp_rect
			(start 0.508 0.9398)
			(end -0.508 -0.9398)
			(stroke
				(width 0)
				(type default)
			)
			(fill no)
			(layer "B.Fab")
		)
		(pad "1" smd custom
			(at 0 -0.4445 270)
			(size 0.1397 0.1397)
			(layers "B.Cu" "B.Mask" "B.Paste")
			(net "P3V3_STBY")
			(options
				(clearance outline)
				(anchor circle)
			)
			(primitives
				(gr_poly
					(pts
						(arc
							(start -0.1778 0.2794)
							(mid -0.249642 0.249642)
							(end -0.2794 0.1778)
						)
						(arc
							(start -0.2794 -0.1778)
							(mid -0.249642 -0.249642)
							(end -0.1778 -0.2794)
						)
						(arc
							(start 0.1778 -0.2794)
							(mid 0.249642 -0.249642)
							(end 0.2794 -0.1778)
						)
						(arc
							(start 0.2794 0.1778)
							(mid 0.249642 0.249642)
							(end 0.1778 0.2794)
						)
					)
					(width 0)
					(fill yes)
				)
			)
		)
		(pad "2" smd custom
			(at 0 0.4445 270)
			(size 0.1397 0.1397)
			(layers "B.Cu" "B.Mask" "B.Paste")
			(net "TCA9555_A2")
			(options
				(clearance outline)
				(anchor circle)
			)
			(primitives
				(gr_poly
					(pts
						(arc
							(start -0.1778 0.2794)
							(mid -0.249642 0.249642)
							(end -0.2794 0.1778)
						)
						(arc
							(start -0.2794 -0.1778)
							(mid -0.249642 -0.249642)
							(end -0.1778 -0.2794)
						)
						(arc
							(start 0.1778 -0.2794)
							(mid 0.249642 -0.249642)
							(end 0.2794 -0.1778)
						)
						(arc
							(start 0.2794 0.1778)
							(mid 0.249642 0.249642)
							(end 0.1778 0.2794)
						)
					)
					(width 0)
					(fill yes)
				)
			)
		)
	)
	(footprint ""
		(layer "B.Cu")
		(at 89.662 -155.6004 90)
		(property "Reference" "C12"
			(at 0 0 90)
			(layer "B.SilkS")
			(hide yes)
			(effects
				(font
					(size 1.27 1.27)
				)
				(justify mirror)
			)
		)
		(property "Value" "SC1U16V2KX-7-GP"
			(at -1.7526 -1.6002 90)
			(unlocked yes)
			(layer "B.Fab")
			(hide yes)
			(effects
				(font
					(size 1.016 1.016)
					(thickness 0.1524)
				)
				(justify mirror)
			)
		)
		(property "Device Type" "C402-TO0D2H24"
			(at -1.7526 -3.1242 90)
			(unlocked yes)
			(layer "B.Fab")
			(hide yes)
			(effects
				(font
					(size 1.016 1.016)
					(thickness 0.1524)
				)
				(justify mirror)
			)
		)
		(duplicate_pad_numbers_are_jumpers no)
		(fp_rect
			(start 0.4826 0.889)
			(end -0.4826 -0.889)
			(stroke
				(width 0)
				(type default)
			)
			(fill no)
			(layer "B.CrtYd")
		)
		(fp_rect
			(start 0.4826 0.889)
			(end -0.4826 -0.889)
			(stroke
				(width 0)
				(type default)
			)
			(fill no)
			(layer "B.Fab")
		)
		(pad "1" smd custom
			(at 0 -0.4572 270)
			(size 0.1524 0.1524)
			(layers "B.Cu" "B.Mask" "B.Paste")
			(net "P3V3_STBY")
			(options
				(clearance outline)
				(anchor circle)
			)
			(primitives
				(gr_poly
					(pts
						(arc
							(start -0.254 -0.3048)
							(mid -0.325842 -0.275042)
							(end -0.3556 -0.2032)
						)
						(arc
							(start -0.3556 0.2032)
							(mid -0.325842 0.275042)
							(end -0.254 0.3048)
						)
						(arc
							(start 0.254 0.3048)
							(mid 0.325842 0.275042)
							(end 0.3556 0.2032)
						)
						(arc
							(start 0.3556 -0.2032)
							(mid 0.325842 -0.275042)
							(end 0.254 -0.3048)
						)
					)
					(width 0)
					(fill yes)
				)
			)
		)
		(pad "2" smd custom
			(at 0 0.4572 270)
			(size 0.1524 0.1524)
			(layers "B.Cu" "B.Mask" "B.Paste")
			(net "GND")
			(options
				(clearance outline)
				(anchor circle)
			)
			(primitives
				(gr_poly
					(pts
						(arc
							(start -0.254 -0.3048)
							(mid -0.325842 -0.275042)
							(end -0.3556 -0.2032)
						)
						(arc
							(start -0.3556 0.2032)
							(mid -0.325842 0.275042)
							(end -0.254 0.3048)
						)
						(arc
							(start 0.254 0.3048)
							(mid 0.325842 0.275042)
							(end 0.3556 0.2032)
						)
						(arc
							(start 0.3556 -0.2032)
							(mid 0.325842 -0.275042)
							(end 0.254 -0.3048)
						)
					)
					(width 0)
					(fill yes)
				)
			)
		)
	)
	(footprint ""
		(layer "B.Cu")
		(at 116.82984 -6.60146 90)
		(property "Reference" "R436"
			(at 0 0 90)
			(layer "B.SilkS")
			(hide yes)
			(effects
				(font
					(size 1.27 1.27)
				)
				(justify mirror)
			)
		)
		(property "Value" "0R2J-2-GP"
			(at -0.064008 -3.993896 90)
			(unlocked yes)
			(layer "B.Fab")
			(hide yes)
			(effects
				(font
					(size 1.016 1.016)
					(thickness 0.1524)
				)
				(justify mirror)
			)
		)
		(property "Device Type" "R402H16"
			(at -0.064008 -5.517896 90)
			(unlocked yes)
			(layer "B.Fab")
			(hide yes)
			(effects
				(font
					(size 1.016 1.016)
					(thickness 0.1524)
				)
				(justify mirror)
			)
		)
		(duplicate_pad_numbers_are_jumpers no)
		(fp_line
			(start 0.508 -0.9398)
			(end 0.508 0.9398)
			(stroke
				(width 0.1524)
				(type default)
			)
			(layer "B.SilkS")
		)
		(fp_line
			(start -0.508 -0.9398)
			(end 0.508 -0.9398)
			(stroke
				(width 0.1524)
				(type default)
			)
			(layer "B.SilkS")
		)
		(fp_rect
			(start 0.508 0.9398)
			(end -0.508 -0.9398)
			(stroke
				(width 0)
				(type default)
			)
			(fill no)
			(layer "B.CrtYd")
		)
		(fp_rect
			(start 0.508 0.9398)
			(end -0.508 -0.9398)
			(stroke
				(width 0)
				(type default)
			)
			(fill no)
			(layer "B.Fab")
		)
		(pad "1" smd custom
			(at 0 -0.4445 270)
			(size 0.1397 0.1397)
			(layers "B.Cu" "B.Mask" "B.Paste")
			(net "P12V_A_PGOOD")
			(options
				(clearance outline)
				(anchor circle)
			)
			(primitives
				(gr_poly
					(pts
						(arc
							(start -0.1778 0.2794)
							(mid -0.249642 0.249642)
							(end -0.2794 0.1778)
						)
						(arc
							(start -0.2794 -0.1778)
							(mid -0.249642 -0.249642)
							(end -0.1778 -0.2794)
						)
						(arc
							(start 0.1778 -0.2794)
							(mid 0.249642 -0.249642)
							(end 0.2794 -0.1778)
						)
						(arc
							(start 0.2794 0.1778)
							(mid 0.249642 0.249642)
							(end 0.1778 0.2794)
						)
					)
					(width 0)
					(fill yes)
				)
			)
		)
		(pad "2" smd custom
			(at 0 0.4445 270)
			(size 0.1397 0.1397)
			(layers "B.Cu" "B.Mask" "B.Paste")
			(net "MB0_HS_ENABLE")
			(options
				(clearance outline)
				(anchor circle)
			)
			(primitives
				(gr_poly
					(pts
						(arc
							(start -0.1778 0.2794)
							(mid -0.249642 0.249642)
							(end -0.2794 0.1778)
						)
						(arc
							(start -0.2794 -0.1778)
							(mid -0.249642 -0.249642)
							(end -0.1778 -0.2794)
						)
						(arc
							(start 0.1778 -0.2794)
							(mid 0.249642 -0.249642)
							(end 0.2794 -0.1778)
						)
						(arc
							(start 0.2794 0.1778)
							(mid 0.249642 0.249642)
							(end 0.1778 0.2794)
						)
					)
					(width 0)
					(fill yes)
				)
			)
		)
	)
)
